(kicad_pcb
	(version 20260206)
	(generator "pcbnew")
	(generator_version "10.0")
	(general
		(thickness 1.6)
		(legacy_teardrops no)
	)
	(paper "A4")
	(title_block
		(title "Wiwynn_Tioga_Pass_MB.brd")
		(comment 1 "Tioga Pass / footprint 153 of 4770 (U25W4), pads 324-434 of 456")
	)
	(layers
		(0 "F.Cu" signal "TOP")
		(4 "In1.Cu" signal "L2GND")
		(6 "In2.Cu" signal "L3")
		(8 "In3.Cu" signal "L4GND")
		(10 "In4.Cu" signal "L5")
		(12 "In5.Cu" signal "L6GND")
		(14 "In6.Cu" signal "L7VCC")
		(16 "In7.Cu" signal "L8VCC")
		(18 "In8.Cu" signal "L9GND")
		(20 "In9.Cu" signal "L10")
		(22 "In10.Cu" signal "L11GND")
		(24 "In11.Cu" signal "L12")
		(26 "In12.Cu" signal "L13GND")
		(2 "B.Cu" signal "BOTTOM")
		(9 "F.Adhes" user "F.Adhesive")
		(11 "B.Adhes" user "B.Adhesive")
		(13 "F.Paste" user "Package Geometry/Pastemask Top")
		(15 "B.Paste" user "Package Geometry/Pastemask Bottom")
		(5 "F.SilkS" user "Ref Des/Silkscreen Top")
		(7 "B.SilkS" user "Ref Des/Silkscreen Bottom")
		(1 "F.Mask" user "Board Geometry/Soldermask Top")
		(3 "B.Mask" user "Board Geometry/Soldermask Bottom")
		(17 "Dwgs.User" user "User.Drawings")
		(19 "Cmts.User" user "User.Comments")
		(21 "Eco1.User" user "User.Eco1")
		(23 "Eco2.User" user "User.Eco2")
		(25 "Edge.Cuts" user "Board Geometry/Outline")
		(27 "Margin" user)
		(31 "F.CrtYd" user "Package Geometry/Place Bound Top")
		(29 "B.CrtYd" user "Package Geometry/Place Bound Bottom")
		(35 "F.Fab" user "Ref Des/Assembly Top")
		(33 "B.Fab" user "Ref Des/Assembly Bottom")
	)
	(footprint ""
		(layer "F.Cu")
		(at 415.490152 -34.934652 90)
		(property "Reference" "U25W4"
			(at 0 0 90)
			(layer "F.SilkS")
			(hide yes)
			(effects
				(font
					(size 1.27 1.27)
				)
			)
		)
		(property "Value" "*"
			(at -17.0307 -8.698992 90)
			(unlocked yes)
			(layer "F.Fab")
			(hide yes)
			(effects
				(font
					(size 1.27 1.016)
					(thickness 0.1524)
				)
			)
		)
		(property "Device Type" "AST2520A1-GP-GP_ASIC2-GB1-AST2A"
			(at -17.0307 -10.222992 90)
			(unlocked yes)
			(layer "F.Fab")
			(hide yes)
			(effects
				(font
					(size 1.27 1.016)
					(thickness 0.1524)
				)
			)
		)
		(duplicate_pad_numbers_are_jumpers no)
		(pad "P13" smd circle
			(at 1.199896 1.999996 90)
			(size 0.3556 0.3556)
			(layers "F.Cu" "F.Mask" "F.Paste")
			(net "P1V15_AUX_BMC")
		)
		(pad "P14" smd circle
			(at 1.999996 1.999996 90)
			(size 0.3556 0.3556)
			(layers "F.Cu" "F.Mask" "F.Paste")
			(net "P1V15_AUX_BMC")
		)
		(pad "P16" smd circle
			(at 3.599942 1.999996 90)
			(size 0.3556 0.3556)
			(layers "F.Cu" "F.Mask" "F.Paste")
			(net "P1V15_AUX_BMC")
		)
		(pad "P17" smd circle
			(at 4.400042 1.999996 90)
			(size 0.3556 0.3556)
			(layers "F.Cu" "F.Mask" "F.Paste")
			(net "VCC_D_3V3")
		)
		(pad "P18" smd circle
			(at 5.199888 1.999996 90)
			(size 0.3556 0.3556)
			(layers "F.Cu" "F.Mask" "F.Paste")
			(net "HSC_SMBUS_SWITCH_EN")
		)
		(pad "P19" smd circle
			(at 5.999988 1.999996 90)
			(size 0.3556 0.3556)
			(layers "F.Cu" "F.Mask" "F.Paste")
			(net "FM_BIOS_POST_CMPLT_N")
		)
		(pad "P20" smd circle
			(at 6.800088 1.999996 90)
			(size 0.3556 0.3556)
			(layers "F.Cu" "F.Mask" "F.Paste")
			(net "SMB_SLOTX24_STBY_LVC3_SDA_R")
		)
		(pad "P21" smd circle
			(at 7.599934 1.999996 90)
			(size 0.3556 0.3556)
			(layers "F.Cu" "F.Mask" "F.Paste")
			(net "FM_BMC_ONCTL_R_N")
		)
		(pad "P22" smd circle
			(at 8.400034 1.999996 90)
			(size 0.3556 0.3556)
			(layers "F.Cu" "F.Mask" "F.Paste")
			(net "BMC_JTAG_SEL_N")
		)
		(pad "R1" smd circle
			(at -8.400034 2.800096 90)
			(size 0.3556 0.3556)
			(layers "F.Cu" "F.Mask" "F.Paste")
			(net "SMB_BMC_PMBUS_STBY_LVC3_SDA_R")
		)
		(pad "R2" smd circle
			(at -7.599934 2.800096 90)
			(size 0.3556 0.3556)
			(layers "F.Cu" "F.Mask" "F.Paste")
			(net "SGPIO_BMC_CLK_R")
		)
		(pad "R3" smd circle
			(at -6.800088 2.800096 90)
			(size 0.3556 0.3556)
			(layers "F.Cu" "F.Mask" "F.Paste")
			(net "I2C_BMC_VGA_DDC_SCL")
		)
		(pad "R4" smd circle
			(at -5.999988 2.800096 90)
			(size 0.3556 0.3556)
			(layers "F.Cu" "F.Mask" "F.Paste")
			(net "BMC_VGA_VSYNC")
		)
		(pad "R5" smd circle
			(at -5.199888 2.800096 90)
			(size 0.3556 0.3556)
			(layers "F.Cu" "F.Mask" "F.Paste")
			(net "SP2_BMC_CM_UART_TX")
		)
		(pad "R6" smd circle
			(at -4.400042 2.800096 90)
			(size 0.3556 0.3556)
			(layers "F.Cu" "F.Mask" "F.Paste")
			(net "VCC_D_3V3")
		)
		(pad "R7" smd circle
			(at -3.599942 2.800096 90)
			(size 0.3556 0.3556)
			(layers "F.Cu" "F.Mask" "F.Paste")
			(net "P1V15_AUX_BMC")
		)
		(pad "R16" smd circle
			(at 3.599942 2.800096 90)
			(size 0.3556 0.3556)
			(layers "F.Cu" "F.Mask" "F.Paste")
			(net "P1V15_AUX_BMC")
		)
		(pad "R17" smd circle
			(at 4.400042 2.800096 90)
			(size 0.3556 0.3556)
			(layers "F.Cu" "F.Mask" "F.Paste")
			(net "VCC_D_3V3")
		)
		(pad "R18" smd circle
			(at 5.199888 2.800096 90)
			(size 0.3556 0.3556)
			(layers "F.Cu" "F.Mask" "F.Paste")
			(net "IRQ_SML0_ALERT_N")
		)
		(pad "R19" smd circle
			(at 5.999988 2.800096 90)
			(size 0.3556 0.3556)
			(layers "F.Cu" "F.Mask" "F.Paste")
			(net "BMC_STRAP_BIT3")
		)
		(pad "R20" smd circle
			(at 6.800088 2.800096 90)
			(size 0.3556 0.3556)
			(layers "F.Cu" "F.Mask" "F.Paste")
			(net "Net_6481")
		)
		(pad "R21" smd circle
			(at 7.599934 2.800096 90)
			(size 0.3556 0.3556)
			(layers "F.Cu" "F.Mask" "F.Paste")
			(net "FM_SLPS4_N")
		)
		(pad "R22" smd circle
			(at 8.400034 2.800096 90)
			(size 0.3556 0.3556)
			(layers "F.Cu" "F.Mask" "F.Paste")
			(net "FM_SLPS3_N")
		)
		(pad "T1" smd circle
			(at -8.400034 3.599942 90)
			(size 0.3556 0.3556)
			(layers "F.Cu" "F.Mask" "F.Paste")
			(net "IRQ_OC_DETECT_N")
		)
		(pad "T2" smd circle
			(at -7.599934 3.599942 90)
			(size 0.3556 0.3556)
			(layers "F.Cu" "F.Mask" "F.Paste")
			(net "IRQ_UV_DETECT_N")
		)
		(pad "T3" smd circle
			(at -6.800088 3.599942 90)
			(size 0.3556 0.3556)
			(layers "F.Cu" "F.Mask" "F.Paste")
			(net "I2C_BMC_VGA_DDC_SDA")
		)
		(pad "T4" smd circle
			(at -5.999988 3.599942 90)
			(size 0.3556 0.3556)
			(layers "F.Cu" "F.Mask" "F.Paste")
			(net "FM_PWRBRK_N")
		)
		(pad "T5" smd circle
			(at -5.199888 3.599942 90)
			(size 0.3556 0.3556)
			(layers "F.Cu" "F.Mask" "F.Paste")
			(net "SP2_BMC_CM_UART_RX")
		)
		(pad "T6" smd circle
			(at -4.400042 3.599942 90)
			(size 0.3556 0.3556)
			(layers "F.Cu" "F.Mask" "F.Paste")
			(net "GND")
		)
		(pad "T7" smd circle
			(at -3.599942 3.599942 90)
			(size 0.3556 0.3556)
			(layers "F.Cu" "F.Mask" "F.Paste")
			(net "GND")
		)
		(pad "T8" smd circle
			(at -2.800096 3.599942 90)
			(size 0.3556 0.3556)
			(layers "F.Cu" "F.Mask" "F.Paste")
			(net "P1V2_AUX_BMC")
		)
		(pad "T9" smd circle
			(at -1.999996 3.599942 90)
			(size 0.3556 0.3556)
			(layers "F.Cu" "F.Mask" "F.Paste")
			(net "BMC_M_VREFCA")
		)
		(pad "T10" smd circle
			(at -1.199896 3.599942 90)
			(size 0.3556 0.3556)
			(layers "F.Cu" "F.Mask" "F.Paste")
			(net "P1V2_AUX_BMC")
		)
		(pad "T11" smd circle
			(at -0.40005 3.599942 90)
			(size 0.3556 0.3556)
			(layers "F.Cu" "F.Mask" "F.Paste")
			(net "VCC_PA_3V3")
		)
		(pad "T12" smd circle
			(at 0.40005 3.599942 90)
			(size 0.3556 0.3556)
			(layers "F.Cu" "F.Mask" "F.Paste")
			(net "P1V2_AUX_BMC")
		)
		(pad "T13" smd circle
			(at 1.199896 3.599942 90)
			(size 0.3556 0.3556)
			(layers "F.Cu" "F.Mask" "F.Paste")
			(net "P1V2_AUX_BMC")
		)
		(pad "T14" smd circle
			(at 1.999996 3.599942 90)
			(size 0.3556 0.3556)
			(layers "F.Cu" "F.Mask" "F.Paste")
			(net "P1V2_AUX_BMC")
		)
		(pad "T15" smd circle
			(at 2.800096 3.599942 90)
			(size 0.3556 0.3556)
			(layers "F.Cu" "F.Mask" "F.Paste")
			(net "VCC_D_3V3")
		)
		(pad "T16" smd circle
			(at 3.599942 3.599942 90)
			(size 0.3556 0.3556)
			(layers "F.Cu" "F.Mask" "F.Paste")
			(net "GND")
		)
		(pad "T17" smd circle
			(at 4.400042 3.599942 90)
			(size 0.3556 0.3556)
			(layers "F.Cu" "F.Mask" "F.Paste")
			(net "BMC_TCK_MUX_SEL")
		)
		(pad "T18" smd circle
			(at 5.199888 3.599942 90)
			(size 0.3556 0.3556)
			(layers "F.Cu" "F.Mask" "F.Paste")
			(net "SPI_BMC_BT_DI")
		)
		(pad "T19" smd circle
			(at 5.999988 3.599942 90)
			(size 0.3556 0.3556)
			(layers "F.Cu" "F.Mask" "F.Paste")
			(net "FM_MP_PS_REDUNDANT_LOST_N")
		)
		(pad "T20" smd circle
			(at 6.800088 3.599942 90)
			(size 0.3556 0.3556)
			(layers "F.Cu" "F.Mask" "F.Paste")
			(net "UV_HIGH_SET")
		)
		(pad "T21" smd circle
			(at 7.599934 3.599942 90)
			(size 0.3556 0.3556)
			(layers "F.Cu" "F.Mask" "F.Paste")
			(net "FM_OCP_MEZZA_PRES")
		)
		(pad "T22" smd circle
			(at 8.400034 3.599942 90)
			(size 0.3556 0.3556)
			(layers "F.Cu" "F.Mask" "F.Paste")
			(net "BMC_SELF_HW_RST")
		)
		(pad "U1" smd circle
			(at -8.400034 4.400042 90)
			(size 0.3556 0.3556)
			(layers "F.Cu" "F.Mask" "F.Paste")
			(net "FM_HSC_TIMER_EXP_N")
		)
		(pad "U2" smd circle
			(at -7.599934 4.400042 90)
			(size 0.3556 0.3556)
			(layers "F.Cu" "F.Mask" "F.Paste")
			(net "FM_BIOS_TOP_SWAP")
		)
		(pad "U3" smd circle
			(at -6.800088 4.400042 90)
			(size 0.3556 0.3556)
			(layers "F.Cu" "F.Mask" "F.Paste")
			(net "FM_CPU_MSMI_LVT3_N")
		)
		(pad "U4" smd circle
			(at -5.999988 4.400042 90)
			(size 0.3556 0.3556)
			(layers "F.Cu" "F.Mask" "F.Paste")
			(net "FAN_TACH1")
		)
		(pad "U5" smd circle
			(at -5.199888 4.400042 90)
			(size 0.3556 0.3556)
			(layers "F.Cu" "F.Mask" "F.Paste")
			(net "FAN_TACH0")
		)
		(pad "U6" smd circle
			(at -4.400042 4.400042 90)
			(size 0.3556 0.3556)
			(layers "F.Cu" "F.Mask" "F.Paste")
			(net "GND")
		)
		(pad "U7" smd circle
			(at -3.599942 4.400042 90)
			(size 0.3556 0.3556)
			(layers "F.Cu" "F.Mask" "F.Paste")
			(net "BMC_M_DQ15")
		)
		(pad "U8" smd circle
			(at -2.800096 4.400042 90)
			(size 0.3556 0.3556)
			(layers "F.Cu" "F.Mask" "F.Paste")
			(net "BMC_M_DM0")
		)
		(pad "U9" smd circle
			(at -1.999996 4.400042 90)
			(size 0.3556 0.3556)
			(layers "F.Cu" "F.Mask" "F.Paste")
			(net "BMC_M_DQ4")
		)
		(pad "U10" smd circle
			(at -1.199896 4.400042 90)
			(size 0.3556 0.3556)
			(layers "F.Cu" "F.Mask" "F.Paste")
			(net "BMC_M_DQ0")
		)
		(pad "U11" smd circle
			(at -0.40005 4.400042 90)
			(size 0.3556 0.3556)
			(layers "F.Cu" "F.Mask" "F.Paste")
			(net "GND")
		)
		(pad "U12" smd circle
			(at 0.40005 4.400042 90)
			(size 0.3556 0.3556)
			(layers "F.Cu" "F.Mask" "F.Paste")
			(net "BMC_M_BA0")
		)
		(pad "U13" smd circle
			(at 1.199896 4.400042 90)
			(size 0.3556 0.3556)
			(layers "F.Cu" "F.Mask" "F.Paste")
			(net "BMC_M_A10")
		)
		(pad "U14" smd circle
			(at 1.999996 4.400042 90)
			(size 0.3556 0.3556)
			(layers "F.Cu" "F.Mask" "F.Paste")
			(net "BMC_M_A3")
		)
		(pad "U15" smd circle
			(at 2.800096 4.400042 90)
			(size 0.3556 0.3556)
			(layers "F.Cu" "F.Mask" "F.Paste")
			(net "TP_BMC_M_A15")
		)
		(pad "U16" smd circle
			(at 3.599942 4.400042 90)
			(size 0.3556 0.3556)
			(layers "F.Cu" "F.Mask" "F.Paste")
			(net "BMC_M_MALERT_N")
		)
		(pad "U17" smd circle
			(at 4.400042 4.400042 90)
			(size 0.3556 0.3556)
			(layers "F.Cu" "F.Mask" "F.Paste")
			(net "SPI_BMC_BT_DO_R")
		)
		(pad "U18" smd circle
			(at 5.199888 4.400042 90)
			(size 0.3556 0.3556)
			(layers "F.Cu" "F.Mask" "F.Paste")
			(net "RST_BMC_SRST_N")
		)
		(pad "U19" smd circle
			(at 5.999988 4.400042 90)
			(size 0.3556 0.3556)
			(layers "F.Cu" "F.Mask" "F.Paste")
			(net "FM_BMC_READY_N")
		)
		(pad "U20" smd circle
			(at 6.800088 4.400042 90)
			(size 0.3556 0.3556)
			(layers "F.Cu" "F.Mask" "F.Paste")
			(net "BMC_STRAP_BIT5")
		)
		(pad "U21" smd circle
			(at 7.599934 4.400042 90)
			(size 0.3556 0.3556)
			(layers "F.Cu" "F.Mask" "F.Paste")
			(net "BMC_STRAP_BIT17")
		)
		(pad "U22" smd circle
			(at 8.400034 4.400042 90)
			(size 0.3556 0.3556)
			(layers "F.Cu" "F.Mask" "F.Paste")
			(net "PECI_SEL")
		)
		(pad "V1" smd circle
			(at -8.400034 5.199888 90)
			(size 0.3556 0.3556)
			(layers "F.Cu" "F.Mask" "F.Paste")
			(net "SP1_BMC_HOST_UART_TX")
		)
		(pad "V2" smd circle
			(at -7.599934 5.199888 90)
			(size 0.3556 0.3556)
			(layers "F.Cu" "F.Mask" "F.Paste")
			(net "FAN_PWM_OUT_SYS0")
		)
		(pad "V3" smd circle
			(at -6.800088 5.199888 90)
			(size 0.3556 0.3556)
			(layers "F.Cu" "F.Mask" "F.Paste")
			(net "FM_BIOS_PREFRB2_GOOD")
		)
		(pad "V4" smd circle
			(at -5.999988 5.199888 90)
			(size 0.3556 0.3556)
			(layers "F.Cu" "F.Mask" "F.Paste")
			(net "FM_BOARD_SKU_ID0")
		)
		(pad "V5" smd circle
			(at -5.199888 5.199888 90)
			(size 0.3556 0.3556)
			(layers "F.Cu" "F.Mask" "F.Paste")
			(net "FAN_TACH2")
		)
		(pad "V6" smd circle
			(at -4.400042 5.199888 90)
			(size 0.3556 0.3556)
			(layers "F.Cu" "F.Mask" "F.Paste")
			(net "BMC_RSMRST_B_N")
		)
		(pad "V7" smd circle
			(at -3.599942 5.199888 90)
			(size 0.3556 0.3556)
			(layers "F.Cu" "F.Mask" "F.Paste")
			(net "BMC_M_DQ14")
		)
		(pad "V8" smd circle
			(at -2.800096 5.199888 90)
			(size 0.3556 0.3556)
			(layers "F.Cu" "F.Mask" "F.Paste")
			(net "GND")
		)
		(pad "V9" smd circle
			(at -1.999996 5.199888 90)
			(size 0.3556 0.3556)
			(layers "F.Cu" "F.Mask" "F.Paste")
			(net "BMC_M_DQ7")
		)
		(pad "V10" smd circle
			(at -1.199896 5.199888 90)
			(size 0.3556 0.3556)
			(layers "F.Cu" "F.Mask" "F.Paste")
			(net "GND")
		)
		(pad "V11" smd circle
			(at -0.40005 5.199888 90)
			(size 0.3556 0.3556)
			(layers "F.Cu" "F.Mask" "F.Paste")
			(net "BMC_M_ODT")
		)
		(pad "V12" smd circle
			(at 0.40005 5.199888 90)
			(size 0.3556 0.3556)
			(layers "F.Cu" "F.Mask" "F.Paste")
			(net "GND")
		)
		(pad "V13" smd circle
			(at 1.199896 5.199888 90)
			(size 0.3556 0.3556)
			(layers "F.Cu" "F.Mask" "F.Paste")
			(net "BMC_M_A0")
		)
		(pad "V14" smd circle
			(at 1.999996 5.199888 90)
			(size 0.3556 0.3556)
			(layers "F.Cu" "F.Mask" "F.Paste")
			(net "GND")
		)
		(pad "V15" smd circle
			(at 2.800096 5.199888 90)
			(size 0.3556 0.3556)
			(layers "F.Cu" "F.Mask" "F.Paste")
			(net "BMC_M_A5")
		)
		(pad "V16" smd circle
			(at 3.599942 5.199888 90)
			(size 0.3556 0.3556)
			(layers "F.Cu" "F.Mask" "F.Paste")
			(net "GND")
		)
		(pad "V17" smd circle
			(at 4.400042 5.199888 90)
			(size 0.3556 0.3556)
			(layers "F.Cu" "F.Mask" "F.Paste")
			(net "P1V15_AUX_BMC")
		)
		(pad "V18" smd circle
			(at 5.199888 5.199888 90)
			(size 0.3556 0.3556)
			(layers "F.Cu" "F.Mask" "F.Paste")
			(net "RST_BMC_EXTRST_N")
		)
		(pad "V19" smd circle
			(at 5.999988 5.199888 90)
			(size 0.3556 0.3556)
			(layers "F.Cu" "F.Mask" "F.Paste")
			(net "RST_BMC_PLTRST_BUF_N")
		)
		(pad "V20" smd circle
			(at 6.800088 5.199888 90)
			(size 0.3556 0.3556)
			(layers "F.Cu" "F.Mask" "F.Paste")
			(net "FM_THROTTLE_N")
		)
		(pad "V21" smd circle
			(at 7.599934 5.199888 90)
			(size 0.3556 0.3556)
			(layers "F.Cu" "F.Mask" "F.Paste")
			(net "IRQ_SML1_PMBUS_ALERT_N")
		)
		(pad "V22" smd circle
			(at 8.400034 5.199888 90)
			(size 0.3556 0.3556)
			(layers "F.Cu" "F.Mask" "F.Paste")
			(net "BMC_STRAP_BIT20")
		)
		(pad "W1" smd circle
			(at -8.400034 5.999988 90)
			(size 0.3556 0.3556)
			(layers "F.Cu" "F.Mask" "F.Paste")
			(net "SP1_BMC_HOST_UART_RX")
		)
		(pad "W2" smd circle
			(at -7.599934 5.999988 90)
			(size 0.3556 0.3556)
			(layers "F.Cu" "F.Mask" "F.Paste")
			(net "FAN_PWM_OUT_SYS1")
		)
		(pad "W3" smd circle
			(at -6.800088 5.999988 90)
			(size 0.3556 0.3556)
			(layers "F.Cu" "F.Mask" "F.Paste")
			(net "FM_BACKUP_BIOS_SEL_N")
		)
		(pad "W4" smd circle
			(at -5.999988 5.999988 90)
			(size 0.3556 0.3556)
			(layers "F.Cu" "F.Mask" "F.Paste")
			(net "FM_XRC_READY_N")
		)
		(pad "W5" smd circle
			(at -5.199888 5.999988 90)
			(size 0.3556 0.3556)
			(layers "F.Cu" "F.Mask" "F.Paste")
			(net "FM_BOARD_SKU_ID1")
		)
		(pad "W6" smd circle
			(at -4.400042 5.999988 90)
			(size 0.3556 0.3556)
			(layers "F.Cu" "F.Mask" "F.Paste")
			(net "BMC_PWR_DEBUG_N")
		)
		(pad "W7" smd circle
			(at -3.599942 5.999988 90)
			(size 0.3556 0.3556)
			(layers "F.Cu" "F.Mask" "F.Paste")
			(net "BMC_M_DQ13")
		)
		(pad "W8" smd circle
			(at -2.800096 5.999988 90)
			(size 0.3556 0.3556)
			(layers "F.Cu" "F.Mask" "F.Paste")
			(net "BMC_M_DQ11")
		)
		(pad "W9" smd circle
			(at -1.999996 5.999988 90)
			(size 0.3556 0.3556)
			(layers "F.Cu" "F.Mask" "F.Paste")
			(net "BMC_M_DQ6")
		)
		(pad "W10" smd circle
			(at -1.199896 5.999988 90)
			(size 0.3556 0.3556)
			(layers "F.Cu" "F.Mask" "F.Paste")
			(net "BMC_M_DQ1")
		)
		(pad "W11" smd circle
			(at -0.40005 5.999988 90)
			(size 0.3556 0.3556)
			(layers "F.Cu" "F.Mask" "F.Paste")
			(net "BMC_MIOZ")
		)
		(pad "W12" smd circle
			(at 0.40005 5.999988 90)
			(size 0.3556 0.3556)
			(layers "F.Cu" "F.Mask" "F.Paste")
			(net "BMC_M_RAS_N")
		)
		(pad "W13" smd circle
			(at 1.199896 5.999988 90)
			(size 0.3556 0.3556)
			(layers "F.Cu" "F.Mask" "F.Paste")
			(net "BMC_M_BG0")
		)
		(pad "W14" smd circle
			(at 1.999996 5.999988 90)
			(size 0.3556 0.3556)
			(layers "F.Cu" "F.Mask" "F.Paste")
			(net "BMC_M_A2")
		)
		(pad "W15" smd circle
			(at 2.800096 5.999988 90)
			(size 0.3556 0.3556)
			(layers "F.Cu" "F.Mask" "F.Paste")
			(net "BMC_M_A4")
		)
		(pad "W16" smd circle
			(at 3.599942 5.999988 90)
			(size 0.3556 0.3556)
			(layers "F.Cu" "F.Mask" "F.Paste")
			(net "BMC_M_A8")
		)
		(pad "W17" smd circle
			(at 4.400042 5.999988 90)
			(size 0.3556 0.3556)
			(layers "F.Cu" "F.Mask" "F.Paste")
			(net "VCC_PA_3V3")
		)
		(pad "W18" smd circle
			(at 5.199888 5.999988 90)
			(size 0.3556 0.3556)
			(layers "F.Cu" "F.Mask" "F.Paste")
			(net "CLK_24M_25M_BMC_CLKIN")
		)
		(pad "W19" smd circle
			(at 5.999988 5.999988 90)
			(size 0.3556 0.3556)
			(layers "F.Cu" "F.Mask" "F.Paste")
			(net "XDP_PRESENT_N")
		)
		(pad "W20" smd circle
			(at 6.800088 5.999988 90)
			(size 0.3556 0.3556)
			(layers "F.Cu" "F.Mask" "F.Paste")
			(net "Net_544")
		)
		(pad "W21" smd circle
			(at 7.599934 5.999988 90)
			(size 0.3556 0.3556)
			(layers "F.Cu" "F.Mask" "F.Paste")
			(net "BMC_STRAP_BIT27")
		)
		(pad "W22" smd circle
			(at 8.400034 5.999988 90)
			(size 0.3556 0.3556)
			(layers "F.Cu" "F.Mask" "F.Paste")
			(net "BMC_STRAP_BIT18")
		)
	)
)
